(kicad_pcb
	(version 20241229)
	(generator "pcbnew")
	(generator_version "9.0")
	(general
		(thickness 1.711)
		(legacy_teardrops no)
	)
	(paper "A4")
	(title_block
		(title "Antmicro Baseboard for Jetson AGX Thor")
		(date "2026-02-18")
		(rev "1.1.0")
		(company "Antmicro Ltd")
		(comment 1 "www.antmicro.com")
		(comment 9 "footprints 1099-1103 of 1170")
	)
	(layers
		(0 "F.Cu" signal)
		(4 "In1.Cu" signal)
		(6 "In2.Cu" signal)
		(8 "In3.Cu" signal)
		(10 "In4.Cu" jumper)
		(12 "In5.Cu" signal)
		(14 "In6.Cu" signal)
		(16 "In7.Cu" signal)
		(18 "In8.Cu" signal)
		(2 "B.Cu" signal)
		(9 "F.Adhes" user "F.Adhesive")
		(11 "B.Adhes" user "B.Adhesive")
		(13 "F.Paste" user)
		(15 "B.Paste" user)
		(5 "F.SilkS" user "F.Silkscreen")
		(7 "B.SilkS" user "B.Silkscreen")
		(1 "F.Mask" user)
		(3 "B.Mask" user)
		(17 "Dwgs.User" user "User.Drawings")
		(19 "Cmts.User" user "User.Comments")
		(21 "Eco1.User" user "User.Eco1")
		(23 "Eco2.User" user "User.Eco2")
		(25 "Edge.Cuts" user)
		(27 "Margin" user)
		(31 "F.CrtYd" user "F.Courtyard")
		(29 "B.CrtYd" user "B.Courtyard")
		(35 "F.Fab" user)
		(33 "B.Fab" user)
	)
	(footprint "antmicro-footprints:SOT-23-5"
		(layer "B.Cu")
		(at 97.75 57 180)
		(property "Reference" "U72"
			(at -4.25 1 0)
			(layer "B.SilkS")
			(effects
				(font
					(size 0.7 0.7)
					(thickness 0.15)
				)
				(justify left bottom mirror)
			)
		)
		(property "Value" "TPS3840PL30DBVR"
			(at 0.002 -2.799 0)
			(layer "B.Fab")
			(effects
				(font
					(size 0.7 0.7)
					(thickness 0.15)
				)
				(justify left bottom mirror)
			)
		)
		(property "Datasheet" "https://www.ti.com/lit/ds/symlink/tps3840.pdf?HQS=dis-mous-null-mousermode-dsf-pf-null-wwe&DCM=yes&ref_url=https%3A%2F%2Fwww.mouser.com%2F&distId=26"
			(at 0 0 0)
			(layer "B.Fab")
			(hide yes)
			(effects
				(font
					(size 1.27 1.27)
					(thickness 0.15)
				)
				(justify mirror)
			)
		)
		(property "Description" "Voltage supervisor"
			(at 0 0 0)
			(layer "B.Fab")
			(hide yes)
			(effects
				(font
					(size 1.27 1.27)
					(thickness 0.15)
				)
				(justify mirror)
			)
		)
		(property "Manufacturer" "Texas Instruments"
			(at 0 0 0)
			(unlocked yes)
			(layer "B.Fab")
			(hide yes)
			(effects
				(font
					(size 1 1)
					(thickness 0.15)
				)
				(justify mirror)
			)
		)
		(property "MPN" "TPS3840PL30DBVR"
			(at 0 0 0)
			(unlocked yes)
			(layer "B.Fab")
			(hide yes)
			(effects
				(font
					(size 1 1)
					(thickness 0.15)
				)
				(justify mirror)
			)
		)
		(property "Author" "Antmicro"
			(at 0 0 0)
			(unlocked yes)
			(layer "B.Fab")
			(hide yes)
			(effects
				(font
					(size 1 1)
					(thickness 0.15)
				)
				(justify mirror)
			)
		)
		(property "License" "Apache-2.0"
			(at 0 0 0)
			(unlocked yes)
			(layer "B.Fab")
			(hide yes)
			(effects
				(font
					(size 1 1)
					(thickness 0.15)
				)
				(justify mirror)
			)
		)
		(property ki_fp_filters "DBV0005A_N DBV0005A_M DBV0005A_L")
		(sheetname "/SoM_Power/")
		(sheetfile "som_power.kicad_sch")
		(attr smd)
		(fp_line
			(start 0.8 1.6)
			(end 0.5 1.6)
			(stroke
				(width 0.15)
				(type solid)
			)
			(layer "B.SilkS")
		)
		(fp_line
			(start 0.8 1.3)
			(end 0.8 1.6)
			(stroke
				(width 0.15)
				(type solid)
			)
			(layer "B.SilkS")
		)
		(fp_line
			(start 0.8 -0.55)
			(end 0.8 0.55)
			(stroke
				(width 0.15)
				(type solid)
			)
			(layer "B.SilkS")
		)
		(fp_line
			(start 0.8 -1.3)
			(end 0.8 -1.599)
			(stroke
				(width 0.15)
				(type solid)
			)
			(layer "B.SilkS")
		)
		(fp_line
			(start 0.8 -1.599)
			(end 0.549 -1.599)
			(stroke
				(width 0.15)
				(type solid)
			)
			(layer "B.SilkS")
		)
		(fp_line
			(start -0.55 -1.6)
			(end -0.85 -1.6)
			(stroke
				(width 0.15)
				(type solid)
			)
			(layer "B.SilkS")
		)
		(fp_line
			(start -0.8 1.6)
			(end -0.5 1.6)
			(stroke
				(width 0.15)
				(type solid)
			)
			(layer "B.SilkS")
		)
		(fp_line
			(start -0.8 1.6)
			(end -0.8 1.3)
			(stroke
				(width 0.15)
				(type solid)
			)
			(layer "B.SilkS")
		)
		(fp_line
			(start -0.85 -1.6)
			(end -0.85 -1.301)
			(stroke
				(width 0.15)
				(type solid)
			)
			(layer "B.SilkS")
		)
		(fp_circle
			(center -1.25 1.5)
			(end -1.2 1.5)
			(stroke
				(width 0.15)
				(type solid)
			)
			(fill yes)
			(layer "B.SilkS")
		)
		(fp_poly
			(pts
				(xy 1.9 1.76) (xy 1.9 -1.75) (xy -1.9 -1.75) (xy -1.9 1.76)
			)
			(stroke
				(width 0.05)
				(type solid)
			)
			(fill no)
			(layer "B.CrtYd")
		)
		(fp_line
			(start -0.398 1.525999)
			(end -0.874 1.05)
			(stroke
				(width 0.15)
				(type solid)
			)
			(layer "B.Fab")
		)
		(fp_poly
			(pts
				(xy 0.874 -1.523) (xy 0.874 1.525) (xy -0.873 1.525) (xy -0.873 -1.523)
			)
			(stroke
				(width 0.15)
				(type solid)
			)
			(fill no)
			(layer "B.Fab")
		)
		(fp_text user "${REFERENCE}"
			(at -1.898 -4.299 0)
			(layer "B.Fab")
			(effects
				(font
					(size 0.7 0.7)
					(thickness 0.15)
				)
				(justify left bottom mirror)
			)
		)
		(fp_text user "License: Apache-2.0"
			(at -1.898 -6.7 0)
			(layer "B.Fab")
			(effects
				(font
					(size 0.7 0.7)
					(thickness 0.15)
				)
				(justify left bottom mirror)
			)
		)
		(fp_text user "Author: Antmicro"
			(at -1.898 -5.499 0)
			(layer "B.Fab")
			(effects
				(font
					(size 0.7 0.7)
					(thickness 0.15)
				)
				(justify left bottom mirror)
			)
		)
		(pad "1" smd rect
			(at -1.351 0.951 270)
			(size 0.55 1)
			(layers "B.Cu" "B.Mask" "B.Paste")
			(net 892 "Net-(Q22-G)")
			(pinfunction "~{RESET}")
			(pintype "output")
		)
		(pad "2" smd rect
			(at -1.351 0 270)
			(size 0.55 1)
			(layers "B.Cu" "B.Mask" "B.Paste")
			(net 4 "+3V3_AON")
			(pinfunction "VDD")
			(pintype "power_in")
		)
		(pad "3" smd rect
			(at -1.351 -0.949 270)
			(size 0.55 1)
			(layers "B.Cu" "B.Mask" "B.Paste")
			(net 1 "GND")
			(pinfunction "GND")
			(pintype "power_in")
		)
		(pad "4" smd rect
			(at 1.35 -0.949 270)
			(size 0.55 1)
			(layers "B.Cu" "B.Mask" "B.Paste")
			(net 1037 "Net-(U72-~{MR})")
			(pinfunction "~{MR}")
			(pintype "input")
		)
		(pad "5" smd rect
			(at 1.35 0.951 270)
			(size 0.55 1)
			(layers "B.Cu" "B.Mask" "B.Paste")
			(net 521 "Net-(U72-CT)")
			(pinfunction "CT")
			(pintype "passive")
		)
	)
	(footprint "antmicro-footprints:Oscillator_SMD_Abracon_AK3LPHEF1_3.2x2.5x1mm"
		(layer "B.Cu")
		(at 103.75 59.25 -90)
		(property "Reference" "Y5"
			(at -1.3 -3.030532 90)
			(layer "B.SilkS")
			(effects
				(font
					(size 0.7 0.7)
					(thickness 0.15)
				)
				(justify left bottom mirror)
			)
		)
		(property "Value" "Oscillator_156.25MHz_AK3LPHEF1"
			(at 0 -3 90)
			(unlocked yes)
			(layer "B.Fab")
			(effects
				(font
					(size 0.7 0.7)
					(thickness 0.15)
				)
				(justify left bottom mirror)
			)
		)
		(property "Datasheet" "https://eu.mouser.com/datasheet/2/3/AK3LP-3318362.pdf"
			(at 0 0 90)
			(layer "B.Fab")
			(hide yes)
			(effects
				(font
					(size 1.27 1.27)
					(thickness 0.15)
				)
				(justify mirror)
			)
		)
		(property "Description" "156.25 MHz XO (Standard) HCSL Oscillator 3.3V Enable/Disable 6-SMD, +/-25ppm"
			(at 0 0 90)
			(layer "B.Fab")
			(hide yes)
			(effects
				(font
					(size 1.27 1.27)
					(thickness 0.15)
				)
				(justify mirror)
			)
		)
		(property "MPN" "AK3LPHEF1-156.2500T"
			(at 0 0 90)
			(unlocked yes)
			(layer "B.Fab")
			(hide yes)
			(effects
				(font
					(size 1 1)
					(thickness 0.15)
				)
				(justify mirror)
			)
		)
		(property "Manufacturer" "Abracon"
			(at 0 0 90)
			(unlocked yes)
			(layer "B.Fab")
			(hide yes)
			(effects
				(font
					(size 1 1)
					(thickness 0.15)
				)
				(justify mirror)
			)
		)
		(property "Val" "156.25MHz"
			(at 0 0 90)
			(unlocked yes)
			(layer "B.Fab")
			(hide yes)
			(effects
				(font
					(size 1 1)
					(thickness 0.15)
				)
				(justify mirror)
			)
		)
		(property "Author" "Antmicro"
			(at 0 0 90)
			(unlocked yes)
			(layer "B.Fab")
			(hide yes)
			(effects
				(font
					(size 1 1)
					(thickness 0.15)
				)
				(justify mirror)
			)
		)
		(property "License" "Apache-2.0"
			(at 0 0 90)
			(unlocked yes)
			(layer "B.Fab")
			(hide yes)
			(effects
				(font
					(size 1 1)
					(thickness 0.15)
				)
				(justify mirror)
			)
		)
		(sheetname "/SoM_IO2/")
		(sheetfile "som_io2.kicad_sch")
		(attr smd)
		(fp_line
			(start 1.25 1.8)
			(end -1.25 1.8)
			(stroke
				(width 0.15)
				(type solid)
			)
			(layer "B.SilkS")
		)
		(fp_line
			(start 1.25 -1.899999)
			(end -1.25 -1.899999)
			(stroke
				(width 0.15)
				(type solid)
			)
			(layer "B.SilkS")
		)
		(fp_circle
			(center -1.525 1.825)
			(end -1.525 1.775)
			(stroke
				(width 0.15)
				(type solid)
			)
			(fill yes)
			(layer "B.SilkS")
		)
		(fp_poly
			(pts
				(xy 1.6 1.9) (xy 1.6 -2) (xy -1.6 -2) (xy -1.6 1.9)
			)
			(stroke
				(width 0.05)
				(type solid)
			)
			(fill no)
			(layer "B.CrtYd")
		)
		(fp_text user "${REFERENCE}"
			(at -2.29 -5.11 90)
			(unlocked yes)
			(layer "B.Fab")
			(effects
				(font
					(size 0.7 0.7)
					(thickness 0.15)
				)
				(justify left bottom mirror)
			)
		)
		(fp_text user "Author: Antmicro"
			(at -2.29 -6.31 90)
			(layer "B.Fab")
			(effects
				(font
					(size 0.7 0.7)
					(thickness 0.15)
				)
				(justify left bottom mirror)
			)
		)
		(fp_text user "License: Apache-2.0"
			(at -2.29 -3.91 90)
			(layer "B.Fab")
			(effects
				(font
					(size 0.7 0.7)
					(thickness 0.15)
				)
				(justify left bottom mirror)
			)
		)
		(pad "1" smd rect
			(at -0.925 1.24)
			(size 0.92 1.05)
			(layers "B.Cu" "B.Mask" "B.Paste")
			(net 1101 "Net-(Y5-EN)")
			(pinfunction "EN")
			(pintype "input")
			(solder_mask_margin 0.05)
		)
		(pad "2" smd rect
			(at -0.925 -0.05)
			(size 0.8 1.05)
			(layers "B.Cu" "B.Mask" "B.Paste")
			(net 1180 "unconnected-(Y5-NC-Pad2)")
			(pinfunction "NC")
			(pintype "no_connect")
			(solder_mask_margin 0.05)
		)
		(pad "3" smd rect
			(at -0.925 -1.34)
			(size 0.92 1.05)
			(layers "B.Cu" "B.Mask" "B.Paste")
			(net 1 "GND")
			(pinfunction "GND")
			(pintype "power_in")
			(solder_mask_margin 0.05)
		)
		(pad "4" smd rect
			(at 0.925 -1.34)
			(size 0.92 1.05)
			(layers "B.Cu" "B.Mask" "B.Paste")
			(net 894 "/SoM_IO2/SFI_CLK+")
			(pinfunction "OUT+")
			(pintype "output")
			(solder_mask_margin 0.05)
		)
		(pad "5" smd rect
			(at 0.925 -0.05)
			(size 0.8 1.05)
			(layers "B.Cu" "B.Mask" "B.Paste")
			(net 895 "/SoM_IO2/SFI_CLK-")
			(pinfunction "OUT-")
			(pintype "output")
			(solder_mask_margin 0.05)
		)
		(pad "6" smd rect
			(at 0.925 1.24)
			(size 0.92 1.05)
			(layers "B.Cu" "B.Mask" "B.Paste")
			(net 2 "+3V3")
			(pinfunction "VCC")
			(pintype "power_in")
			(solder_mask_margin 0.05)
		)
	)
	(footprint "antmicro-footprints:R_0402_1005Metric"
		(layer "B.Cu")
		(at 162.84 59.81 90)
		(descr "Resistor SMD 0402")
		(tags "resistor SMD 0402")
		(property "Reference" "R72"
			(at 3.11 -0.34 90)
			(layer "B.SilkS")
			(effects
				(font
					(size 0.7 0.7)
					(thickness 0.15)
				)
				(justify right top mirror)
			)
		)
		(property "Value" "R_10k_0402"
			(at -1.011843 -1.772047 90)
			(layer "B.Fab")
			(effects
				(font
					(size 0.7 0.7)
					(thickness 0.15)
				)
				(justify right top mirror)
			)
		)
		(property "Datasheet" "https://www.bourns.com/docs/product-datasheets/cr.pdf"
			(at 0 0 90)
			(layer "B.Fab")
			(hide yes)
			(effects
				(font
					(size 1.27 1.27)
					(thickness 0.15)
				)
				(justify mirror)
			)
		)
		(property "Description" "SMD Chip Resistor, 10 kohm, ± 1%, 62.5 mW, 0402 [1005 Metric], Thick Film, General Purpose"
			(at 0 0 90)
			(layer "B.Fab")
			(hide yes)
			(effects
				(font
					(size 1.27 1.27)
					(thickness 0.15)
				)
				(justify mirror)
			)
		)
		(property "MPN" "CR0402-FX-1002GLF"
			(at 0 0 270)
			(unlocked yes)
			(layer "B.Fab")
			(hide yes)
			(effects
				(font
					(size 1 1)
					(thickness 0.15)
				)
				(justify mirror)
			)
		)
		(property "Manufacturer" "Bourns"
			(at 0 0 270)
			(unlocked yes)
			(layer "B.Fab")
			(hide yes)
			(effects
				(font
					(size 1 1)
					(thickness 0.15)
				)
				(justify mirror)
			)
		)
		(property "License" "Apache-2.0"
			(at 0 0 270)
			(unlocked yes)
			(layer "B.Fab")
			(hide yes)
			(effects
				(font
					(size 1 1)
					(thickness 0.15)
				)
				(justify mirror)
			)
		)
		(property "Author" "Antmicro"
			(at 0 0 270)
			(unlocked yes)
			(layer "B.Fab")
			(hide yes)
			(effects
				(font
					(size 1 1)
					(thickness 0.15)
				)
				(justify mirror)
			)
		)
		(property "Val" "10k"
			(at 0 0 270)
			(unlocked yes)
			(layer "B.Fab")
			(hide yes)
			(effects
				(font
					(size 1 1)
					(thickness 0.15)
				)
				(justify mirror)
			)
		)
		(property "Tolerance" "1%"
			(at 0 0 270)
			(unlocked yes)
			(layer "B.Fab")
			(hide yes)
			(effects
				(font
					(size 1 1)
					(thickness 0.15)
				)
				(justify mirror)
			)
		)
		(sheetname "/Power/")
		(sheetfile "power.kicad_sch")
		(attr smd)
		(fp_rect
			(start -0.925 0.47)
			(end 0.925 -0.47)
			(stroke
				(width 0.05)
				(type default)
			)
			(fill no)
			(layer "B.CrtYd")
		)
		(fp_rect
			(start -0.5 0.25)
			(end 0.5 -0.25)
			(stroke
				(width 0.15)
				(type solid)
			)
			(fill no)
			(layer "B.Fab")
		)
		(fp_text user "Author: Antmicro"
			(at -0.95 -4.169 90)
			(layer "B.Fab")
			(effects
				(font
					(size 0.7 0.7)
					(thickness 0.15)
				)
				(justify right top mirror)
			)
		)
		(fp_text user "License: Apache-2.0"
			(at -0.95 -5.169 90)
			(layer "B.Fab")
			(effects
				(font
					(size 0.7 0.7)
					(thickness 0.15)
				)
				(justify right top mirror)
			)
		)
		(fp_text user "${REFERENCE}"
			(at -0.95 -3.168 90)
			(layer "B.Fab")
			(effects
				(font
					(size 0.7 0.7)
					(thickness 0.15)
				)
				(justify right top mirror)
			)
		)
		(pad "1" smd roundrect
			(at -0.48 0 90)
			(size 0.59 0.64)
			(layers "B.Cu" "B.Mask" "B.Paste")
			(roundrect_rratio 0.25)
			(net 1 "GND")
			(pintype "passive")
		)
		(pad "2" smd roundrect
			(at 0.48 0 90)
			(size 0.59 0.64)
			(layers "B.Cu" "B.Mask" "B.Paste")
			(roundrect_rratio 0.25)
			(net 282 "+1V15")
			(pintype "passive")
		)
	)
	(footprint "antmicro-footprints:R_0402_1005Metric"
		(layer "B.Cu")
		(at 208.716532 142)
		(descr "Resistor SMD 0402")
		(tags "resistor SMD 0402")
		(property "Reference" "R192"
			(at 0.98 -0.31 0)
			(layer "B.SilkS")
			(effects
				(font
					(size 0.7 0.7)
					(thickness 0.15)
				)
				(justify right top mirror)
			)
		)
		(property "Value" "R_1k_0402"
			(at -1.011843 -1.772047 0)
			(layer "B.Fab")
			(effects
				(font
					(size 0.7 0.7)
					(thickness 0.15)
				)
				(justify right top mirror)
			)
		)
		(property "Datasheet" "https://www.bourns.com/docs/product-datasheets/cr.pdf"
			(at 0 0 0)
			(layer "B.Fab")
			(hide yes)
			(effects
				(font
					(size 1.27 1.27)
					(thickness 0.15)
				)
				(justify mirror)
			)
		)
		(property "Description" "SMD Chip Resistor, 1 kohm, ± 1%, 63 mW, 0402 [1005 Metric], Thick Film, General Purpose"
			(at 0 0 0)
			(layer "B.Fab")
			(hide yes)
			(effects
				(font
					(size 1.27 1.27)
					(thickness 0.15)
				)
				(justify mirror)
			)
		)
		(property "MPN" "CR0402-FX-1001GLF"
			(at 0 0 180)
			(unlocked yes)
			(layer "B.Fab")
			(hide yes)
			(effects
				(font
					(size 1 1)
					(thickness 0.15)
				)
				(justify mirror)
			)
		)
		(property "Manufacturer" "Bourns"
			(at 0 0 180)
			(unlocked yes)
			(layer "B.Fab")
			(hide yes)
			(effects
				(font
					(size 1 1)
					(thickness 0.15)
				)
				(justify mirror)
			)
		)
		(property "License" "Apache-2.0"
			(at 0 0 180)
			(unlocked yes)
			(layer "B.Fab")
			(hide yes)
			(effects
				(font
					(size 1 1)
					(thickness 0.15)
				)
				(justify mirror)
			)
		)
		(property "Author" "Antmicro"
			(at 0 0 180)
			(unlocked yes)
			(layer "B.Fab")
			(hide yes)
			(effects
				(font
					(size 1 1)
					(thickness 0.15)
				)
				(justify mirror)
			)
		)
		(property "Val" "1k"
			(at 0 0 180)
			(unlocked yes)
			(layer "B.Fab")
			(hide yes)
			(effects
				(font
					(size 1 1)
					(thickness 0.15)
				)
				(justify mirror)
			)
		)
		(property "Tolerance" "1%"
			(at 0 0 180)
			(unlocked yes)
			(layer "B.Fab")
			(hide yes)
			(effects
				(font
					(size 1 1)
					(thickness 0.15)
				)
				(justify mirror)
			)
		)
		(sheetname "/SFP/")
		(sheetfile "sfp.kicad_sch")
		(attr smd)
		(fp_rect
			(start -0.925 0.47)
			(end 0.925 -0.47)
			(stroke
				(width 0.05)
				(type default)
			)
			(fill no)
			(layer "B.CrtYd")
		)
		(fp_rect
			(start -0.5 0.25)
			(end 0.5 -0.25)
			(stroke
				(width 0.15)
				(type solid)
			)
			(fill no)
			(layer "B.Fab")
		)
		(fp_text user "Author: Antmicro"
			(at -0.95 -4.169 0)
			(layer "B.Fab")
			(effects
				(font
					(size 0.7 0.7)
					(thickness 0.15)
				)
				(justify right top mirror)
			)
		)
		(fp_text user "License: Apache-2.0"
			(at -0.95 -5.169 0)
			(layer "B.Fab")
			(effects
				(font
					(size 0.7 0.7)
					(thickness 0.15)
				)
				(justify right top mirror)
			)
		)
		(fp_text user "${REFERENCE}"
			(at -0.95 -3.168 0)
			(layer "B.Fab")
			(effects
				(font
					(size 0.7 0.7)
					(thickness 0.15)
				)
				(justify right top mirror)
			)
		)
		(pad "1" smd roundrect
			(at -0.48 0)
			(size 0.59 0.64)
			(layers "B.Cu" "B.Mask" "B.Paste")
			(roundrect_rratio 0.25)
			(net 1370 "Net-(J12-RX_{LOS})")
			(pintype "passive")
		)
		(pad "2" smd roundrect
			(at 0.48 0)
			(size 0.59 0.64)
			(layers "B.Cu" "B.Mask" "B.Paste")
			(roundrect_rratio 0.25)
			(net 2 "+3V3")
			(pintype "passive")
		)
	)
	(footprint "antmicro-footprints:TP_SMD_0.75mm"
		(layer "B.Cu")
		(at 89.15 61.5 180)
		(property "Reference" "TP119"
			(at 0.38 -0.45 0)
			(layer "B.SilkS")
			(effects
				(font
					(size 0.7 0.7)
					(thickness 0.15)
				)
				(justify left bottom mirror)
			)
		)
		(property "Value" "TP_0.75mm_SMD"
			(at 0 -1.2 0)
			(layer "B.Fab")
			(effects
				(font
					(size 0.7 0.7)
					(thickness 0.15)
				)
				(justify left bottom mirror)
			)
		)
		(property "Description" "SMT test point"
			(at 0 0 0)
			(layer "B.Fab")
			(hide yes)
			(effects
				(font
					(size 1.27 1.27)
					(thickness 0.15)
				)
				(justify mirror)
			)
		)
		(property "MPN" ""
			(at 0 0 0)
			(unlocked yes)
			(layer "B.Fab")
			(hide yes)
			(effects
				(font
					(size 1 1)
					(thickness 0.15)
				)
				(justify mirror)
			)
		)
		(property "Manufacturer" ""
			(at 0 0 0)
			(unlocked yes)
			(layer "B.Fab")
			(hide yes)
			(effects
				(font
					(size 1 1)
					(thickness 0.15)
				)
				(justify mirror)
			)
		)
		(property "Author" "Antmicro"
			(at 0 0 0)
			(unlocked yes)
			(layer "B.Fab")
			(hide yes)
			(effects
				(font
					(size 1 1)
					(thickness 0.15)
				)
				(justify mirror)
			)
		)
		(property "License" "Apache-2.0"
			(at 0 0 0)
			(unlocked yes)
			(layer "B.Fab")
			(hide yes)
			(effects
				(font
					(size 1 1)
					(thickness 0.15)
				)
				(justify mirror)
			)
		)
		(sheetname "/SoM_Power/")
		(sheetfile "som_power.kicad_sch")
		(attr exclude_from_pos_files exclude_from_bom)
		(fp_circle
			(center 0 0)
			(end 0.475 0)
			(stroke
				(width 0.05)
				(type default)
			)
			(fill no)
			(layer "B.CrtYd")
		)
		(fp_text user "Author: Antmicro"
			(at -0.4 -3.901 0)
			(layer "B.Fab")
			(effects
				(font
					(size 0.7 0.7)
					(thickness 0.15)
				)
				(justify left bottom mirror)
			)
		)
		(fp_text user "${REFERENCE}"
			(at -0.4 -2.7 0)
			(layer "B.Fab")
			(effects
				(font
					(size 0.7 0.7)
					(thickness 0.15)
				)
				(justify left bottom mirror)
			)
		)
		(fp_text user "License: Apache-2.0"
			(at -0.4 -5.101 0)
			(layer "B.Fab")
			(effects
				(font
					(size 0.7 0.7)
					(thickness 0.15)
				)
				(justify left bottom mirror)
			)
		)
		(pad "1" smd circle
			(at 0 0 180)
			(size 0.75 0.75)
			(layers "B.Cu" "B.Mask")
			(net 1027 "Net-(U70-~{CLR})")
			(pinfunction "1")
			(pintype "passive")
		)
	)
)
